(kicad_pcb
	(version 20241229)
	(generator "pcbnew")
	(generator_version "9.0")
	(general
		(thickness 1.292)
		(legacy_teardrops no)
	)
	(paper "A4")
	(title_block
		(title "LPDDR5 Testbed")
		(date "2023-12-19")
		(rev "1.0.0")
		(comment 9 "footprints 54-58 of 160")
	)
	(layers
		(0 "F.Cu" signal)
		(4 "In1.Cu" power)
		(6 "In2.Cu" power)
		(8 "In3.Cu" signal)
		(10 "In4.Cu" signal)
		(2 "B.Cu" signal)
		(9 "F.Adhes" user "F.Adhesive")
		(11 "B.Adhes" user "B.Adhesive")
		(13 "F.Paste" user)
		(15 "B.Paste" user)
		(5 "F.SilkS" user "F.Silkscreen")
		(7 "B.SilkS" user "B.Silkscreen")
		(1 "F.Mask" user)
		(3 "B.Mask" user)
		(17 "Dwgs.User" user "User.Drawings")
		(19 "Cmts.User" user "User.Comments")
		(21 "Eco1.User" user "User.Eco1")
		(23 "Eco2.User" user "User.Eco2")
		(25 "Edge.Cuts" user)
		(27 "Margin" user)
		(31 "F.CrtYd" user "F.Courtyard")
		(29 "B.CrtYd" user "B.Courtyard")
		(35 "F.Fab" user)
		(33 "B.Fab" user)
	)
	(footprint "antmicro-footprints:QFN-20-4EP_3x4x0.75mm_P0.5mm_Layout4x6_LT3033"
		(layer "F.Cu")
		(at 164.075 67.95 90)
		(property "Reference" "U9"
			(at -1.05 -4.075 0)
			(unlocked yes)
			(layer "F.SilkS")
			(effects
				(font
					(size 0.7 0.7)
					(thickness 0.15)
				)
				(justify left bottom)
			)
		)
		(property "Value" "LT3033EUDC_QFN"
			(at 0 3.4 90)
			(unlocked yes)
			(layer "F.Fab")
			(effects
				(font
					(size 0.7 0.7)
					(thickness 0.15)
				)
				(justify left bottom)
			)
		)
		(property "Author" "Antmicro"
			(at 232.025 -96.125 0)
			(layer "F.Fab")
			(hide yes)
			(effects
				(font
					(size 1 1)
					(thickness 0.15)
				)
			)
		)
		(property "License" "Apache-2.0"
			(at 232.025 -96.125 0)
			(layer "F.Fab")
			(hide yes)
			(effects
				(font
					(size 1 1)
					(thickness 0.15)
				)
			)
		)
		(property "MPN" "LT3033EUDC#PBF"
			(at 232.025 -96.125 0)
			(layer "F.Fab")
			(hide yes)
			(effects
				(font
					(size 1 1)
					(thickness 0.15)
				)
			)
		)
		(property "Manufacturer" "Analog Devices"
			(at 232.025 -96.125 0)
			(layer "F.Fab")
			(hide yes)
			(effects
				(font
					(size 1 1)
					(thickness 0.15)
				)
			)
		)
		(sheetname "Power supply")
		(sheetfile "power_supply.kicad_sch")
		(attr smd)
		(fp_line
			(start 1.6 -2.1)
			(end 1 -2.1)
			(stroke
				(width 0.15)
				(type solid)
			)
			(layer "F.SilkS")
		)
		(fp_line
			(start 1.6 -2.1)
			(end 1.6 -1.7)
			(stroke
				(width 0.15)
				(type solid)
			)
			(layer "F.SilkS")
		)
		(fp_line
			(start -1 -2.1)
			(end -1.6 -2.1)
			(stroke
				(width 0.15)
				(type solid)
			)
			(layer "F.SilkS")
		)
		(fp_line
			(start -1.6 -2.1)
			(end -1.6 -1.7)
			(stroke
				(width 0.15)
				(type solid)
			)
			(layer "F.SilkS")
		)
		(fp_line
			(start 1.6 2.1)
			(end 1.6 1.7)
			(stroke
				(width 0.15)
				(type solid)
			)
			(layer "F.SilkS")
		)
		(fp_line
			(start 1 2.1)
			(end 1.6 2.1)
			(stroke
				(width 0.15)
				(type solid)
			)
			(layer "F.SilkS")
		)
		(fp_line
			(start -1.6 2.1)
			(end -1.6 1.7)
			(stroke
				(width 0.15)
				(type solid)
			)
			(layer "F.SilkS")
		)
		(fp_line
			(start -1.6 2.1)
			(end -1 2.1)
			(stroke
				(width 0.15)
				(type solid)
			)
			(layer "F.SilkS")
		)
		(fp_circle
			(center -1.75 -1.55)
			(end -1.7 -1.55)
			(stroke
				(width 0.15)
				(type solid)
			)
			(fill yes)
			(layer "F.SilkS")
		)
		(fp_rect
			(start -2 -2.5)
			(end 2 2.5)
			(stroke
				(width 0.05)
				(type solid)
			)
			(fill no)
			(layer "F.CrtYd")
		)
		(fp_line
			(start 1.5 -2)
			(end -1 -2)
			(stroke
				(width 0.15)
				(type solid)
			)
			(layer "F.Fab")
		)
		(fp_line
			(start -1 -2)
			(end -1.5 -1.5)
			(stroke
				(width 0.15)
				(type solid)
			)
			(layer "F.Fab")
		)
		(fp_line
			(start -1.5 -1.5)
			(end -1.5 2)
			(stroke
				(width 0.15)
				(type solid)
			)
			(layer "F.Fab")
		)
		(fp_line
			(start 1.5 2)
			(end 1.5 -2)
			(stroke
				(width 0.15)
				(type solid)
			)
			(layer "F.Fab")
		)
		(fp_line
			(start -1.5 2)
			(end 1.5 2)
			(stroke
				(width 0.15)
				(type solid)
			)
			(layer "F.Fab")
		)
		(pad "1" smd roundrect
			(at -1.4 -1.25 180)
			(size 0.25 0.7)
			(layers "F.Cu" "F.Mask" "F.Paste")
			(roundrect_rratio 0.25)
			(net 1 "+1V1")
			(pinfunction "IN")
			(pintype "power_in")
		)
		(pad "2" smd roundrect
			(at -1.4 -0.75 180)
			(size 0.25 0.7)
			(layers "F.Cu" "F.Mask" "F.Paste")
			(roundrect_rratio 0.25)
			(net 1 "+1V1")
			(pinfunction "IN")
			(pintype "passive")
		)
		(pad "3" smd roundrect
			(at -1.4 -0.25 180)
			(size 0.25 0.7)
			(layers "F.Cu" "F.Mask" "F.Paste")
			(roundrect_rratio 0.25)
			(net 11 "/Power supply/VOUT")
			(pinfunction "OUT")
			(pintype "passive")
		)
		(pad "4" smd roundrect
			(at -1.4 0.25 180)
			(size 0.25 0.7)
			(layers "F.Cu" "F.Mask" "F.Paste")
			(roundrect_rratio 0.25)
			(net 11 "/Power supply/VOUT")
			(pinfunction "OUT")
			(pintype "passive")
		)
		(pad "5" smd roundrect
			(at -1.4 0.75 180)
			(size 0.25 0.7)
			(layers "F.Cu" "F.Mask" "F.Paste")
			(roundrect_rratio 0.25)
			(net 14 "GND")
			(pinfunction "GND")
			(pintype "power_in")
		)
		(pad "6" smd roundrect
			(at -1.4 1.25 180)
			(size 0.25 0.7)
			(layers "F.Cu" "F.Mask" "F.Paste")
			(roundrect_rratio 0.25)
			(net 14 "GND")
			(pinfunction "GND")
			(pintype "passive")
		)
		(pad "7" smd roundrect
			(at -0.75 1.9 270)
			(size 0.25 0.7)
			(layers "F.Cu" "F.Mask" "F.Paste")
			(roundrect_rratio 0.25)
			(net 14 "GND")
			(pinfunction "ILIM")
			(pintype "passive")
		)
		(pad "8" smd roundrect
			(at -0.25 1.9 270)
			(size 0.25 0.7)
			(layers "F.Cu" "F.Mask" "F.Paste")
			(roundrect_rratio 0.25)
			(net 69 "Net-(R32-Pad2)")
			(pinfunction "IMON")
			(pintype "output")
		)
		(pad "9" smd roundrect
			(at 0.25 1.9 270)
			(size 0.25 0.7)
			(layers "F.Cu" "F.Mask" "F.Paste")
			(roundrect_rratio 0.25)
			(net 6 "Net-(C13-Pad2)")
			(pinfunction "REF/BYP")
			(pintype "passive")
		)
		(pad "10" smd roundrect
			(at 0.75 1.9 270)
			(size 0.25 0.7)
			(layers "F.Cu" "F.Mask" "F.Paste")
			(roundrect_rratio 0.25)
			(net 52 "Net-(POT1-Pad2)")
			(pinfunction "ADJ")
			(pintype "input")
		)
		(pad "11" smd roundrect
			(at 1.4 1.25 180)
			(size 0.25 0.7)
			(layers "F.Cu" "F.Mask" "F.Paste")
			(roundrect_rratio 0.25)
			(net 41 "/Power supply/PWRGD")
			(pinfunction "PWRGD")
			(pintype "open_collector")
		)
		(pad "12" smd roundrect
			(at 1.4 0.75 180)
			(size 0.25 0.7)
			(layers "F.Cu" "F.Mask" "F.Paste")
			(roundrect_rratio 0.25)
			(net 61 "Net-(R29-Pad2)")
			(pinfunction "~{SHDN}")
			(pintype "input")
		)
		(pad "13" smd roundrect
			(at 1.4 0.25 180)
			(size 0.25 0.7)
			(layers "F.Cu" "F.Mask" "F.Paste")
			(roundrect_rratio 0.25)
			(net 11 "/Power supply/VOUT")
			(pinfunction "OUT")
			(pintype "power_out")
		)
		(pad "14" smd roundrect
			(at 1.4 -0.25 180)
			(size 0.25 0.7)
			(layers "F.Cu" "F.Mask" "F.Paste")
			(roundrect_rratio 0.25)
			(net 11 "/Power supply/VOUT")
			(pinfunction "OUT")
			(pintype "passive")
		)
		(pad "15" smd roundrect
			(at 1.4 -0.75 180)
			(size 0.25 0.7)
			(layers "F.Cu" "F.Mask" "F.Paste")
			(roundrect_rratio 0.25)
			(net 1 "+1V1")
			(pinfunction "IN")
			(pintype "passive")
		)
		(pad "16" smd roundrect
			(at 1.4 -1.25 180)
			(size 0.25 0.7)
			(layers "F.Cu" "F.Mask" "F.Paste")
			(roundrect_rratio 0.25)
			(net 1 "+1V1")
			(pinfunction "IN")
			(pintype "passive")
		)
		(pad "17" smd roundrect
			(at 0.75 -1.9 270)
			(size 0.25 0.7)
			(layers "F.Cu" "F.Mask" "F.Paste")
			(roundrect_rratio 0.25)
			(net 11 "/Power supply/VOUT")
			(pinfunction "OUT")
			(pintype "passive")
		)
		(pad "18" smd roundrect
			(at 0.25 -1.9 270)
			(size 0.25 0.7)
			(layers "F.Cu" "F.Mask" "F.Paste")
			(roundrect_rratio 0.25)
			(net 11 "/Power supply/VOUT")
			(pinfunction "OUT")
			(pintype "passive")
		)
		(pad "19" smd roundrect
			(at -0.25 -1.9 270)
			(size 0.25 0.7)
			(layers "F.Cu" "F.Mask" "F.Paste")
			(roundrect_rratio 0.25)
			(net 11 "/Power supply/VOUT")
			(pinfunction "OUT")
			(pintype "passive")
		)
		(pad "20" smd roundrect
			(at -0.75 -1.9 270)
			(size 0.25 0.7)
			(layers "F.Cu" "F.Mask" "F.Paste")
			(roundrect_rratio 0.25)
			(net 11 "/Power supply/VOUT")
			(pinfunction "OUT")
			(pintype "passive")
		)
		(pad "21" smd roundrect
			(at -0.61 -1.12 270)
			(size 0.41 0.25)
			(layers "F.Cu" "F.Mask" "F.Paste")
			(roundrect_rratio 0.25)
			(net 1 "+1V1")
			(pinfunction "IN")
			(pintype "passive")
		)
		(pad "22" smd roundrect
			(at 0.61 -1.12 270)
			(size 0.41 0.25)
			(layers "F.Cu" "F.Mask" "F.Paste")
			(roundrect_rratio 0.25)
			(net 1 "+1V1")
			(pinfunction "IN")
			(pintype "passive")
		)
		(pad "23" smd roundrect
			(at -0.61 -0.02 270)
			(size 0.41 0.25)
			(layers "F.Cu" "F.Mask" "F.Paste")
			(roundrect_rratio 0.25)
			(net 11 "/Power supply/VOUT")
			(pinfunction "OUT")
			(pintype "passive")
		)
		(pad "24" smd roundrect
			(at 0.61 -0.02 270)
			(size 0.41 0.25)
			(layers "F.Cu" "F.Mask" "F.Paste")
			(roundrect_rratio 0.25)
			(net 11 "/Power supply/VOUT")
			(pinfunction "OUT")
			(pintype "passive")
		)
	)
	(footprint "antmicro-footprints:R_Array_4x0402_Panasonic_EXB28V"
		(layer "F.Cu")
		(at 115.875 93.8)
		(property "Reference" "R5"
			(at -1.301 -1.45 0)
			(unlocked yes)
			(layer "F.SilkS")
			(effects
				(font
					(size 0.7 0.7)
					(thickness 0.15)
				)
				(justify left bottom)
			)
		)
		(property "Value" "R_4x100R_0402_array"
			(at -1.5 2 0)
			(layer "F.Fab")
			(effects
				(font
					(size 0.7 0.7)
					(thickness 0.15)
				)
				(justify left bottom)
			)
		)
		(property "Author" "Antmicro"
			(at 0 0 0)
			(layer "F.Fab")
			(hide yes)
			(effects
				(font
					(size 1 1)
					(thickness 0.15)
				)
			)
		)
		(property "License" "Apache-2.0"
			(at 0 0 0)
			(layer "F.Fab")
			(hide yes)
			(effects
				(font
					(size 1 1)
					(thickness 0.15)
				)
			)
		)
		(property "MPN" "EXB-28V101JX"
			(at 0 0 0)
			(layer "F.Fab")
			(hide yes)
			(effects
				(font
					(size 1 1)
					(thickness 0.15)
				)
			)
		)
		(property "Manufacturer" "Panasonic"
			(at 0 0 0)
			(layer "F.Fab")
			(hide yes)
			(effects
				(font
					(size 1 1)
					(thickness 0.15)
				)
			)
		)
		(property "Val" "R_4x100R_0402"
			(at 0 0 0)
			(layer "F.Fab")
			(hide yes)
			(effects
				(font
					(size 1 1)
					(thickness 0.15)
				)
			)
		)
		(sheetname "Translators")
		(sheetfile "translators.kicad_sch")
		(attr smd)
		(fp_line
			(start -1.25 -0.5)
			(end -1.25 0.498)
			(stroke
				(width 0.15)
				(type solid)
			)
			(layer "F.SilkS")
		)
		(fp_line
			(start 1.25 0.499)
			(end 1.25 -0.499)
			(stroke
				(width 0.15)
				(type solid)
			)
			(layer "F.SilkS")
		)
		(fp_rect
			(start -1.25 -0.8)
			(end 1.25 0.8)
			(stroke
				(width 0.05)
				(type solid)
			)
			(fill no)
			(layer "F.CrtYd")
		)
		(fp_line
			(start -1 -0.5)
			(end 0.998 -0.5)
			(stroke
				(width 0.15)
				(type solid)
			)
			(layer "F.Fab")
		)
		(fp_line
			(start -1 0.498)
			(end -1 -0.5)
			(stroke
				(width 0.15)
				(type solid)
			)
			(layer "F.Fab")
		)
		(fp_line
			(start 0.998 -0.5)
			(end 0.998 0.498)
			(stroke
				(width 0.15)
				(type solid)
			)
			(layer "F.Fab")
		)
		(fp_line
			(start 0.998 0.498)
			(end -1 0.498)
			(stroke
				(width 0.15)
				(type solid)
			)
			(layer "F.Fab")
		)
		(pad "1" smd roundrect
			(at -0.8875 0.45)
			(size 0.525 0.5)
			(layers "F.Cu" "F.Mask" "F.Paste")
			(roundrect_rratio 0.25)
			(net 176 "/SODIMM/LPDDR5_IN_A.DQ5")
			(pinfunction "R1.1")
			(pintype "passive")
		)
		(pad "2" smd roundrect
			(at -0.25 0.45)
			(size 0.25 0.5)
			(layers "F.Cu" "F.Mask" "F.Paste")
			(roundrect_rratio 0.25)
			(net 175 "/SODIMM/LPDDR5_IN_A.DQ4")
			(pinfunction "R2.1")
			(pintype "passive")
		)
		(pad "3" smd roundrect
			(at 0.25 0.45)
			(size 0.25 0.5)
			(layers "F.Cu" "F.Mask" "F.Paste")
			(roundrect_rratio 0.25)
			(net 174 "/SODIMM/LPDDR5_IN_A.DQ6")
			(pinfunction "R3.1")
			(pintype "passive")
		)
		(pad "4" smd roundrect
			(at 0.8875 0.45)
			(size 0.525 0.5)
			(layers "F.Cu" "F.Mask" "F.Paste")
			(roundrect_rratio 0.25)
			(net 173 "/SODIMM/LPDDR5_IN_A.DQ7")
			(pinfunction "R4.1")
			(pintype "passive")
		)
		(pad "5" smd roundrect
			(at 0.8875 -0.45)
			(size 0.525 0.5)
			(layers "F.Cu" "F.Mask" "F.Paste")
			(roundrect_rratio 0.25)
			(net 195 "/LPDDR5/LPDDR5_A.DQ7")
			(pinfunction "R4.2")
			(pintype "passive")
		)
		(pad "6" smd roundrect
			(at 0.25 -0.45)
			(size 0.25 0.5)
			(layers "F.Cu" "F.Mask" "F.Paste")
			(roundrect_rratio 0.25)
			(net 196 "/LPDDR5/LPDDR5_A.DQ6")
			(pinfunction "R3.2")
			(pintype "passive")
		)
		(pad "7" smd roundrect
			(at -0.25 -0.45)
			(size 0.25 0.5)
			(layers "F.Cu" "F.Mask" "F.Paste")
			(roundrect_rratio 0.25)
			(net 198 "/LPDDR5/LPDDR5_A.DQ4")
			(pinfunction "R2.2")
			(pintype "passive")
		)
		(pad "8" smd roundrect
			(at -0.8875 -0.45)
			(size 0.525 0.5)
			(layers "F.Cu" "F.Mask" "F.Paste")
			(roundrect_rratio 0.25)
			(net 197 "/LPDDR5/LPDDR5_A.DQ5")
			(pinfunction "R1.2")
			(pintype "passive")
		)
	)
	(footprint "antmicro-footprints:R_0402_1005Metric"
		(layer "F.Cu")
		(at 137.65 93.85 90)
		(descr "Resistor SMD 0402")
		(tags "resistor SMD 0402")
		(property "Reference" "R68"
			(at -1.15 1.35 90)
			(unlocked yes)
			(layer "F.SilkS")
			(effects
				(font
					(size 0.7 0.7)
					(thickness 0.15)
				)
				(justify left bottom)
			)
		)
		(property "Value" "R_100R_0402"
			(at -1.011843 1.772047 90)
			(layer "F.Fab")
			(effects
				(font
					(size 0.7 0.7)
					(thickness 0.15)
				)
				(justify left bottom)
			)
		)
		(property "Author" "Antmicro"
			(at 231.5 -43.8 0)
			(layer "F.Fab")
			(hide yes)
			(effects
				(font
					(size 1 1)
					(thickness 0.15)
				)
			)
		)
		(property "License" "Apache-2.0"
			(at 231.5 -43.8 0)
			(layer "F.Fab")
			(hide yes)
			(effects
				(font
					(size 1 1)
					(thickness 0.15)
				)
			)
		)
		(property "MPN" "CR0402-FX-1000GLF"
			(at 231.5 -43.8 0)
			(layer "F.Fab")
			(hide yes)
			(effects
				(font
					(size 1 1)
					(thickness 0.15)
				)
			)
		)
		(property "Manufacturer" "Bourns"
			(at 231.5 -43.8 0)
			(layer "F.Fab")
			(hide yes)
			(effects
				(font
					(size 1 1)
					(thickness 0.15)
				)
			)
		)
		(property "Tolerance" "1%"
			(at 231.5 -43.8 0)
			(layer "F.Fab")
			(hide yes)
			(effects
				(font
					(size 1 1)
					(thickness 0.15)
				)
			)
		)
		(property "Val" "100R"
			(at 231.5 -43.8 0)
			(layer "F.Fab")
			(hide yes)
			(effects
				(font
					(size 1 1)
					(thickness 0.15)
				)
			)
		)
		(sheetname "Translators1")
		(sheetfile "translators.kicad_sch")
		(attr smd)
		(fp_rect
			(start -0.93 -0.47)
			(end 0.93 0.47)
			(stroke
				(width 0.05)
				(type solid)
			)
			(fill no)
			(layer "F.CrtYd")
		)
		(fp_rect
			(start -0.5 -0.25)
			(end 0.5 0.25)
			(stroke
				(width 0.15)
				(type solid)
			)
			(fill no)
			(layer "F.Fab")
		)
		(pad "1" smd roundrect
			(at -0.485 0 90)
			(size 0.59 0.64)
			(layers "F.Cu" "F.Mask" "F.Paste")
			(roundrect_rratio 0.25)
			(net 153 "/SODIMM/LPDDR5_IN_B.CK_N")
			(pintype "passive")
		)
		(pad "2" smd roundrect
			(at 0.485 0 90)
			(size 0.59 0.64)
			(layers "F.Cu" "F.Mask" "F.Paste")
			(roundrect_rratio 0.25)
			(net 113 "/LPDDR5/LPDDR5_B.CK_N")
			(pintype "passive")
		)
	)
	(footprint "antmicro-footprints:TP_SMD_0.75mm"
		(layer "F.Cu")
		(at 109.775 62.95)
		(property "Reference" "TP5"
			(at 0.7 0.4 0)
			(unlocked yes)
			(layer "F.SilkS")
			(effects
				(font
					(size 0.7 0.7)
					(thickness 0.15)
				)
				(justify left bottom)
			)
		)
		(property "Value" "TP_0.75mm_SMD"
			(at 0 1.2 0)
			(layer "F.Fab")
			(effects
				(font
					(size 0.7 0.7)
					(thickness 0.15)
				)
				(justify left bottom)
			)
		)
		(property "Author" "Antmicro"
			(at 0 0 0)
			(layer "F.Fab")
			(hide yes)
			(effects
				(font
					(size 1 1)
					(thickness 0.15)
				)
			)
		)
		(property "License" "Apache-2.0"
			(at 0 0 0)
			(layer "F.Fab")
			(hide yes)
			(effects
				(font
					(size 1 1)
					(thickness 0.15)
				)
			)
		)
		(property "MPN" ""
			(at 0 0 0)
			(layer "F.Fab")
			(hide yes)
			(effects
				(font
					(size 1 1)
					(thickness 0.15)
				)
			)
		)
		(property "Manufacturer" ""
			(at 0 0 0)
			(layer "F.Fab")
			(hide yes)
			(effects
				(font
					(size 1 1)
					(thickness 0.15)
				)
			)
		)
		(sheetname "Power supply")
		(sheetfile "power_supply.kicad_sch")
		(attr exclude_from_pos_files)
		(pad "1" smd circle
			(at 0 0)
			(size 0.75 0.75)
			(layers "F.Cu" "F.Mask")
			(net 8 "/Power supply/VOUT2")
			(pinfunction "1")
			(pintype "passive")
		)
	)
	(footprint "antmicro-footprints:R_0402_1005Metric"
		(layer "F.Cu")
		(at 164.45 93.8 90)
		(descr "Resistor SMD 0402")
		(tags "resistor SMD 0402")
		(property "Reference" "R95"
			(at -1.8 -1.05 0)
			(unlocked yes)
			(layer "F.SilkS")
			(effects
				(font
					(size 0.7 0.7)
					(thickness 0.15)
				)
				(justify left bottom)
			)
		)
		(property "Value" "R_100R_0402"
			(at -1.011843 1.772047 90)
			(layer "F.Fab")
			(effects
				(font
					(size 0.7 0.7)
					(thickness 0.15)
				)
				(justify left bottom)
			)
		)
		(property "Author" "Antmicro"
			(at 258.25 -70.65 0)
			(layer "F.Fab")
			(hide yes)
			(effects
				(font
					(size 1 1)
					(thickness 0.15)
				)
			)
		)
		(property "License" "Apache-2.0"
			(at 258.25 -70.65 0)
			(layer "F.Fab")
			(hide yes)
			(effects
				(font
					(size 1 1)
					(thickness 0.15)
				)
			)
		)
		(property "MPN" "CR0402-FX-1000GLF"
			(at 258.25 -70.65 0)
			(layer "F.Fab")
			(hide yes)
			(effects
				(font
					(size 1 1)
					(thickness 0.15)
				)
			)
		)
		(property "Manufacturer" "Bourns"
			(at 258.25 -70.65 0)
			(layer "F.Fab")
			(hide yes)
			(effects
				(font
					(size 1 1)
					(thickness 0.15)
				)
			)
		)
		(property "Tolerance" "1%"
			(at 258.25 -70.65 0)
			(layer "F.Fab")
			(hide yes)
			(effects
				(font
					(size 1 1)
					(thickness 0.15)
				)
			)
		)
		(property "Val" "100R"
			(at 258.25 -70.65 0)
			(layer "F.Fab")
			(hide yes)
			(effects
				(font
					(size 1 1)
					(thickness 0.15)
				)
			)
		)
		(sheetname "Translators1")
		(sheetfile "translators.kicad_sch")
		(attr smd)
		(fp_rect
			(start -0.93 -0.47)
			(end 0.93 0.47)
			(stroke
				(width 0.05)
				(type solid)
			)
			(fill no)
			(layer "F.CrtYd")
		)
		(fp_rect
			(start -0.5 -0.25)
			(end 0.5 0.25)
			(stroke
				(width 0.15)
				(type solid)
			)
			(fill no)
			(layer "F.Fab")
		)
		(pad "1" smd roundrect
			(at -0.485 0 90)
			(size 0.59 0.64)
			(layers "F.Cu" "F.Mask" "F.Paste")
			(roundrect_rratio 0.25)
			(net 120 "/SODIMM/LPDDR5_IN_B.DMI0")
			(pintype "passive")
		)
		(pad "2" smd roundrect
			(at 0.485 0 90)
			(size 0.59 0.64)
			(layers "F.Cu" "F.Mask" "F.Paste")
			(roundrect_rratio 0.25)
			(net 212 "/LPDDR5/LPDDR5_B.DMI0")
			(pintype "passive")
		)
	)
)
